(kicad_pcb
	(version 20260206)
	(generator "pcbnew")
	(generator_version "10.0")
	(general
		(thickness 1.6)
		(legacy_teardrops no)
	)
	(paper "A4")
	(title_block
		(title "04192023_DAF0TMB3IC0_F0TG_MB_C_brd_V02_OCP.brd")
		(comment 1 "Grand Teton / footprint 3955 of 8354 (U25), pads 3668-3777 of 6102")
	)
	(layers
		(0 "F.Cu" signal "TOP")
		(4 "In1.Cu" signal "GND")
		(6 "In2.Cu" signal "IN1")
		(8 "In3.Cu" signal "GND1")
		(10 "In4.Cu" signal "IN2")
		(12 "In5.Cu" signal "GND2")
		(14 "In6.Cu" signal "IN3")
		(16 "In7.Cu" signal "GND3")
		(18 "In8.Cu" signal "VCC")
		(20 "In9.Cu" signal "VCC1")
		(22 "In10.Cu" signal "GND4")
		(24 "In11.Cu" signal "IN4")
		(26 "In12.Cu" signal "GND5")
		(28 "In13.Cu" signal "IN5")
		(30 "In14.Cu" signal "GND6")
		(32 "In15.Cu" signal "IN6")
		(34 "In16.Cu" signal "GND7")
		(2 "B.Cu" signal "BOTTOM")
		(9 "F.Adhes" user "F.Adhesive")
		(11 "B.Adhes" user "B.Adhesive")
		(13 "F.Paste" user "Package Geometry/Pastemask Top")
		(15 "B.Paste" user "Package Geometry/Pastemask Bottom")
		(5 "F.SilkS" user "Ref Des/Silkscreen Top")
		(7 "B.SilkS" user "Ref Des/Silkscreen Bottom")
		(1 "F.Mask" user "Board Geometry/Soldermask Top")
		(3 "B.Mask" user "Board Geometry/Soldermask Bottom")
		(17 "Dwgs.User" user "User.Drawings")
		(19 "Cmts.User" user "User.Comments")
		(21 "Eco1.User" user "User.Eco1")
		(23 "Eco2.User" user "User.Eco2")
		(25 "Edge.Cuts" user "Board Geometry/Outline")
		(27 "Margin" user)
		(31 "F.CrtYd" user "Package Geometry/Place Bound Top")
		(29 "B.CrtYd" user "Package Geometry/Place Bound Bottom")
		(35 "F.Fab" user "Ref Des/Assembly Top")
		(33 "B.Fab" user "Ref Des/Assembly Bottom")
	)
	(footprint ""
		(layer "F.Cu")
		(at 359.867962 -258.880102 180)
		(property "Reference" "U25"
			(at -45.78477 -62.086744 0)
			(unlocked yes)
			(layer "F.SilkS")
			(effects
				(font
					(size 0.7874 0.5842)
					(thickness 0.1524)
				)
			)
		)
		(property "Value" ""
			(at 0 0 180)
			(layer "F.Fab")
			(effects
				(font
					(size 1.27 1.27)
				)
			)
		)
		(duplicate_pad_numbers_are_jumpers no)
		(pad "CM70" smd circle
			(at 29.93009 23.040086 180)
			(size 0.450088 0.450088)
			(layers "F.Cu" "F.Mask" "F.Paste")
			(net "M_E_CPU0_SB_DQ<12>")
		)
		(pad "CM71" smd circle
			(at 30.86989 23.040086 180)
			(size 0.450088 0.450088)
			(layers "F.Cu" "F.Mask" "F.Paste")
			(net "GND")
		)
		(pad "CM72" smd circle
			(at 31.809944 23.040086 180)
			(size 0.450088 0.450088)
			(layers "F.Cu" "F.Mask" "F.Paste")
			(net "M_A_CPU0_SB_DQS_DP<6>")
		)
		(pad "CM73" smd circle
			(at 32.749998 23.040086 180)
			(size 0.450088 0.450088)
			(layers "F.Cu" "F.Mask" "F.Paste")
			(net "GND")
		)
		(pad "CM74" smd circle
			(at 33.690052 23.040086 180)
			(size 0.450088 0.450088)
			(layers "F.Cu" "F.Mask" "F.Paste")
			(net "M_A_CPU0_SB_DQ<12>")
		)
		(pad "CN1" smd circle
			(at -34.459926 23.850092 180)
			(size 0.450088 0.450088)
			(layers "F.Cu" "F.Mask" "F.Paste")
			(net "GND")
		)
		(pad "CN2" smd circle
			(at -33.519872 23.850092 180)
			(size 0.450088 0.450088)
			(layers "F.Cu" "F.Mask" "F.Paste")
			(net "M_G_CPU0_SB_DQ<14>")
		)
		(pad "CN3" smd circle
			(at -32.580072 23.850092 180)
			(size 0.450088 0.450088)
			(layers "F.Cu" "F.Mask" "F.Paste")
			(net "M_G_CPU0_SB_DQ<13>")
		)
		(pad "CN4" smd circle
			(at -31.640018 23.850092 180)
			(size 0.450088 0.450088)
			(layers "F.Cu" "F.Mask" "F.Paste")
			(net "PVDD11_S3_P0")
		)
		(pad "CN5" smd circle
			(at -30.699964 23.850092 180)
			(size 0.450088 0.450088)
			(layers "F.Cu" "F.Mask" "F.Paste")
			(net "M_K_CPU0_SB_DQ<14>")
		)
		(pad "CN6" smd circle
			(at -29.75991 23.850092 180)
			(size 0.450088 0.450088)
			(layers "F.Cu" "F.Mask" "F.Paste")
			(net "GND")
		)
		(pad "CN7" smd circle
			(at -28.82011 23.850092 180)
			(size 0.450088 0.450088)
			(layers "F.Cu" "F.Mask" "F.Paste")
			(net "M_K_CPU0_SB_DQ<13>")
		)
		(pad "CN8" smd circle
			(at -27.880056 23.850092 180)
			(size 0.450088 0.450088)
			(layers "F.Cu" "F.Mask" "F.Paste")
			(net "GND")
		)
		(pad "CN9" smd circle
			(at -26.940002 23.850092 180)
			(size 0.450088 0.450088)
			(layers "F.Cu" "F.Mask" "F.Paste")
			(net "M_L_CPU0_SB_DQ<14>")
		)
		(pad "CN10" smd circle
			(at -25.999948 23.850092 180)
			(size 0.450088 0.450088)
			(layers "F.Cu" "F.Mask" "F.Paste")
			(net "M_L_CPU0_SB_DQ<13>")
		)
		(pad "CN11" smd circle
			(at -25.059894 23.850092 180)
			(size 0.450088 0.450088)
			(layers "F.Cu" "F.Mask" "F.Paste")
			(net "PVDD11_S3_P0")
		)
		(pad "CN12" smd circle
			(at -24.120094 23.850092 180)
			(size 0.450088 0.450088)
			(layers "F.Cu" "F.Mask" "F.Paste")
			(net "M_H_CPU0_SB_DQ<14>")
		)
		(pad "CN13" smd circle
			(at -23.18004 23.850092 180)
			(size 0.450088 0.450088)
			(layers "F.Cu" "F.Mask" "F.Paste")
			(net "GND")
		)
		(pad "CN14" smd circle
			(at -22.239986 23.850092 180)
			(size 0.450088 0.450088)
			(layers "F.Cu" "F.Mask" "F.Paste")
			(net "M_H_CPU0_SB_DQ<13>")
		)
		(pad "CN15" smd circle
			(at -21.299932 23.850092 180)
			(size 0.450088 0.450088)
			(layers "F.Cu" "F.Mask" "F.Paste")
			(net "GND")
		)
		(pad "CN16" smd circle
			(at -20.359878 23.850092 180)
			(size 0.450088 0.450088)
			(layers "F.Cu" "F.Mask" "F.Paste")
			(net "M_J_CPU0_SB_DQ<14>")
		)
		(pad "CN17" smd circle
			(at -19.420078 23.850092 180)
			(size 0.450088 0.450088)
			(layers "F.Cu" "F.Mask" "F.Paste")
			(net "M_J_CPU0_SB_DQ<13>")
		)
		(pad "CN18" smd circle
			(at -18.480024 23.850092 180)
			(size 0.450088 0.450088)
			(layers "F.Cu" "F.Mask" "F.Paste")
			(net "PVDD11_S3_P0")
		)
		(pad "CN19" smd circle
			(at -17.53997 23.850092 180)
			(size 0.450088 0.450088)
			(layers "F.Cu" "F.Mask" "F.Paste")
			(net "M_I_CPU0_SB_DQ<14>")
		)
		(pad "CN20" smd circle
			(at -16.599916 23.850092 180)
			(size 0.450088 0.450088)
			(layers "F.Cu" "F.Mask" "F.Paste")
			(net "GND")
		)
		(pad "CN21" smd circle
			(at -15.660116 23.850092 180)
			(size 0.450088 0.450088)
			(layers "F.Cu" "F.Mask" "F.Paste")
			(net "M_I_CPU0_SB_DQ<13>")
		)
		(pad "CN22" smd circle
			(at -14.720062 23.850092 180)
			(size 0.450088 0.450088)
			(layers "F.Cu" "F.Mask" "F.Paste")
			(net "GND")
		)
		(pad "CN23" smd circle
			(at -13.780008 23.850092 180)
			(size 0.450088 0.450088)
			(layers "F.Cu" "F.Mask" "F.Paste")
			(net "P5E_CPU0_P2_RX_DP<15>")
		)
		(pad "CN24" smd circle
			(at -12.839954 23.850092 180)
			(size 0.450088 0.450088)
			(layers "F.Cu" "F.Mask" "F.Paste")
			(net "P5E_CPU0_P2_RX_DN<15>")
		)
		(pad "CN25" smd circle
			(at -11.8999 23.850092 180)
			(size 0.450088 0.450088)
			(layers "F.Cu" "F.Mask" "F.Paste")
			(net "GND")
		)
		(pad "CN26" smd circle
			(at -10.9601 23.850092 180)
			(size 0.450088 0.450088)
			(layers "F.Cu" "F.Mask" "F.Paste")
			(net "P5E_CPU0_P2_RX_DP<12>")
		)
		(pad "CN27" smd circle
			(at -10.020046 23.850092 180)
			(size 0.450088 0.450088)
			(layers "F.Cu" "F.Mask" "F.Paste")
			(net "P5E_CPU0_P2_RX_DN<12>")
		)
		(pad "CN28" smd circle
			(at -9.079992 23.850092 180)
			(size 0.450088 0.450088)
			(layers "F.Cu" "F.Mask" "F.Paste")
			(net "GND")
		)
		(pad "CN29" smd circle
			(at -8.139938 23.850092 180)
			(size 0.450088 0.450088)
			(layers "F.Cu" "F.Mask" "F.Paste")
			(net "P5E_CPU0_P2_RX_DP<6>")
		)
		(pad "CN30" smd circle
			(at -7.199884 23.850092 180)
			(size 0.450088 0.450088)
			(layers "F.Cu" "F.Mask" "F.Paste")
			(net "P5E_CPU0_P2_RX_DN<6>")
		)
		(pad "CN31" smd circle
			(at -6.260084 23.850092 180)
			(size 0.450088 0.450088)
			(layers "F.Cu" "F.Mask" "F.Paste")
			(net "GND")
		)
		(pad "CN32" smd circle
			(at -5.32003 23.850092 180)
			(size 0.450088 0.450088)
			(layers "F.Cu" "F.Mask" "F.Paste")
			(net "P5E_CPU0_P2_RX_DP<3>")
		)
		(pad "CN33" smd circle
			(at -4.379976 23.850092 180)
			(size 0.450088 0.450088)
			(layers "F.Cu" "F.Mask" "F.Paste")
			(net "P5E_CPU0_P2_RX_DN<3>")
		)
		(pad "CN34" smd circle
			(at -3.439922 23.850092 180)
			(size 0.450088 0.450088)
			(layers "F.Cu" "F.Mask" "F.Paste")
			(net "GND")
		)
		(pad "CN35" smd circle
			(at -2.500122 23.850092 180)
			(size 0.450088 0.450088)
			(layers "F.Cu" "F.Mask" "F.Paste")
			(net "PVDDCR_CPU1_P0")
		)
		(pad "CN36" smd circle
			(at -1.560068 23.850092 180)
			(size 0.450088 0.450088)
			(layers "F.Cu" "F.Mask" "F.Paste")
			(net "PVDDCR_CPU1_P0")
		)
		(pad "CN40" smd circle
			(at 1.260094 23.850092 180)
			(size 0.450088 0.450088)
			(layers "F.Cu" "F.Mask" "F.Paste")
			(net "PVDDCR_CPU1_P0")
		)
		(pad "CN41" smd circle
			(at 2.199894 23.850092 180)
			(size 0.450088 0.450088)
			(layers "F.Cu" "F.Mask" "F.Paste")
			(net "PVDDCR_CPU1_P0")
		)
		(pad "CN42" smd circle
			(at 3.139948 23.850092 180)
			(size 0.450088 0.450088)
			(layers "F.Cu" "F.Mask" "F.Paste")
			(net "GND")
		)
		(pad "CN43" smd circle
			(at 4.080002 23.850092 180)
			(size 0.450088 0.450088)
			(layers "F.Cu" "F.Mask" "F.Paste")
			(net "P5E_CPU0_P0_TX_DN<12>")
		)
		(pad "CN44" smd circle
			(at 5.020056 23.850092 180)
			(size 0.450088 0.450088)
			(layers "F.Cu" "F.Mask" "F.Paste")
			(net "P5E_CPU0_P0_TX_DP<12>")
		)
		(pad "CN45" smd circle
			(at 5.96011 23.850092 180)
			(size 0.450088 0.450088)
			(layers "F.Cu" "F.Mask" "F.Paste")
			(net "GND")
		)
		(pad "CN46" smd circle
			(at 6.89991 23.850092 180)
			(size 0.450088 0.450088)
			(layers "F.Cu" "F.Mask" "F.Paste")
			(net "P5E_CPU0_P0_TX_DN<9>")
		)
		(pad "CN47" smd circle
			(at 7.839964 23.850092 180)
			(size 0.450088 0.450088)
			(layers "F.Cu" "F.Mask" "F.Paste")
			(net "P5E_CPU0_P0_TX_DP<9>")
		)
		(pad "CN48" smd circle
			(at 8.780018 23.850092 180)
			(size 0.450088 0.450088)
			(layers "F.Cu" "F.Mask" "F.Paste")
			(net "GND")
		)
		(pad "CN49" smd circle
			(at 9.720072 23.850092 180)
			(size 0.450088 0.450088)
			(layers "F.Cu" "F.Mask" "F.Paste")
			(net "P5E_CPU0_P0_TX_DN<3>")
		)
		(pad "CN50" smd circle
			(at 10.659872 23.850092 180)
			(size 0.450088 0.450088)
			(layers "F.Cu" "F.Mask" "F.Paste")
			(net "P5E_CPU0_P0_TX_DP<3>")
		)
		(pad "CN51" smd circle
			(at 11.599926 23.850092 180)
			(size 0.450088 0.450088)
			(layers "F.Cu" "F.Mask" "F.Paste")
			(net "GND")
		)
		(pad "CN52" smd circle
			(at 12.53998 23.850092 180)
			(size 0.450088 0.450088)
			(layers "F.Cu" "F.Mask" "F.Paste")
			(net "P5E_CPU0_P0_TX_DN<0>")
		)
		(pad "CN53" smd circle
			(at 13.480034 23.850092 180)
			(size 0.450088 0.450088)
			(layers "F.Cu" "F.Mask" "F.Paste")
			(net "P5E_CPU0_P0_TX_DP<0>")
		)
		(pad "CN54" smd circle
			(at 14.420088 23.850092 180)
			(size 0.450088 0.450088)
			(layers "F.Cu" "F.Mask" "F.Paste")
			(net "GND")
		)
		(pad "CN55" smd circle
			(at 15.359888 23.850092 180)
			(size 0.450088 0.450088)
			(layers "F.Cu" "F.Mask" "F.Paste")
			(net "M_C_CPU0_SB_DQ<13>")
		)
		(pad "CN56" smd circle
			(at 16.299942 23.850092 180)
			(size 0.450088 0.450088)
			(layers "F.Cu" "F.Mask" "F.Paste")
			(net "GND")
		)
		(pad "CN57" smd circle
			(at 17.239996 23.850092 180)
			(size 0.450088 0.450088)
			(layers "F.Cu" "F.Mask" "F.Paste")
			(net "M_C_CPU0_SB_DQ<14>")
		)
		(pad "CN58" smd circle
			(at 18.18005 23.850092 180)
			(size 0.450088 0.450088)
			(layers "F.Cu" "F.Mask" "F.Paste")
			(net "PVDDIO_P0")
		)
		(pad "CN59" smd circle
			(at 19.120104 23.850092 180)
			(size 0.450088 0.450088)
			(layers "F.Cu" "F.Mask" "F.Paste")
			(net "M_D_CPU0_SB_DQ<13>")
		)
		(pad "CN60" smd circle
			(at 20.059904 23.850092 180)
			(size 0.450088 0.450088)
			(layers "F.Cu" "F.Mask" "F.Paste")
			(net "M_D_CPU0_SB_DQ<14>")
		)
		(pad "CN61" smd circle
			(at 20.999958 23.850092 180)
			(size 0.450088 0.450088)
			(layers "F.Cu" "F.Mask" "F.Paste")
			(net "GND")
		)
		(pad "CN62" smd circle
			(at 21.940012 23.850092 180)
			(size 0.450088 0.450088)
			(layers "F.Cu" "F.Mask" "F.Paste")
			(net "M_B_CPU0_SB_DQ<13>")
		)
		(pad "CN63" smd circle
			(at 22.880066 23.850092 180)
			(size 0.450088 0.450088)
			(layers "F.Cu" "F.Mask" "F.Paste")
			(net "GND")
		)
		(pad "CN64" smd circle
			(at 23.82012 23.850092 180)
			(size 0.450088 0.450088)
			(layers "F.Cu" "F.Mask" "F.Paste")
			(net "M_B_CPU0_SB_DQ<14>")
		)
		(pad "CN65" smd circle
			(at 24.75992 23.850092 180)
			(size 0.450088 0.450088)
			(layers "F.Cu" "F.Mask" "F.Paste")
			(net "PVDDIO_P0")
		)
		(pad "CN66" smd circle
			(at 25.699974 23.850092 180)
			(size 0.450088 0.450088)
			(layers "F.Cu" "F.Mask" "F.Paste")
			(net "M_F_CPU0_SB_DQ<13>")
		)
		(pad "CN67" smd circle
			(at 26.640028 23.850092 180)
			(size 0.450088 0.450088)
			(layers "F.Cu" "F.Mask" "F.Paste")
			(net "M_F_CPU0_SB_DQ<14>")
		)
		(pad "CN68" smd circle
			(at 27.580082 23.850092 180)
			(size 0.450088 0.450088)
			(layers "F.Cu" "F.Mask" "F.Paste")
			(net "GND")
		)
		(pad "CN69" smd circle
			(at 28.519882 23.850092 180)
			(size 0.450088 0.450088)
			(layers "F.Cu" "F.Mask" "F.Paste")
			(net "M_E_CPU0_SB_DQ<13>")
		)
		(pad "CN70" smd circle
			(at 29.459936 23.850092 180)
			(size 0.450088 0.450088)
			(layers "F.Cu" "F.Mask" "F.Paste")
			(net "GND")
		)
		(pad "CN71" smd circle
			(at 30.39999 23.850092 180)
			(size 0.450088 0.450088)
			(layers "F.Cu" "F.Mask" "F.Paste")
			(net "M_E_CPU0_SB_DQ<14>")
		)
		(pad "CN72" smd circle
			(at 31.340044 23.850092 180)
			(size 0.450088 0.450088)
			(layers "F.Cu" "F.Mask" "F.Paste")
			(net "PVDDIO_P0")
		)
		(pad "CN73" smd circle
			(at 32.280098 23.850092 180)
			(size 0.450088 0.450088)
			(layers "F.Cu" "F.Mask" "F.Paste")
			(net "M_A_CPU0_SB_DQ<13>")
		)
		(pad "CN74" smd circle
			(at 33.219898 23.850092 180)
			(size 0.450088 0.450088)
			(layers "F.Cu" "F.Mask" "F.Paste")
			(net "M_A_CPU0_SB_DQ<14>")
		)
		(pad "CN75" smd circle
			(at 34.159952 23.850092 180)
			(size 0.450088 0.450088)
			(layers "F.Cu" "F.Mask" "F.Paste")
			(net "GND")
		)
		(pad "CP2" smd circle
			(at -33.990026 24.660098 180)
			(size 0.450088 0.450088)
			(layers "F.Cu" "F.Mask" "F.Paste")
			(net "M_G_CPU0_SB_DQ<16>")
		)
		(pad "CP3" smd circle
			(at -33.049972 24.660098 180)
			(size 0.450088 0.450088)
			(layers "F.Cu" "F.Mask" "F.Paste")
			(net "GND")
		)
		(pad "CP4" smd circle
			(at -32.109918 24.660098 180)
			(size 0.450088 0.450088)
			(layers "F.Cu" "F.Mask" "F.Paste")
			(net "M_G_CPU0_SB_DQ<15>")
		)
		(pad "CP5" smd circle
			(at -31.170118 24.660098 180)
			(size 0.450088 0.450088)
			(layers "F.Cu" "F.Mask" "F.Paste")
			(net "GND")
		)
		(pad "CP6" smd circle
			(at -30.230064 24.660098 180)
			(size 0.450088 0.450088)
			(layers "F.Cu" "F.Mask" "F.Paste")
			(net "M_K_CPU0_SB_DQ<16>")
		)
		(pad "CP7" smd circle
			(at -29.29001 24.660098 180)
			(size 0.450088 0.450088)
			(layers "F.Cu" "F.Mask" "F.Paste")
			(net "M_K_CPU0_SB_DQ<15>")
		)
		(pad "CP8" smd circle
			(at -28.349956 24.660098 180)
			(size 0.450088 0.450088)
			(layers "F.Cu" "F.Mask" "F.Paste")
			(net "GND")
		)
		(pad "CP9" smd circle
			(at -27.409902 24.660098 180)
			(size 0.450088 0.450088)
			(layers "F.Cu" "F.Mask" "F.Paste")
			(net "M_L_CPU0_SB_DQ<16>")
		)
		(pad "CP10" smd circle
			(at -26.470102 24.660098 180)
			(size 0.450088 0.450088)
			(layers "F.Cu" "F.Mask" "F.Paste")
			(net "GND")
		)
		(pad "CP11" smd circle
			(at -25.530048 24.660098 180)
			(size 0.450088 0.450088)
			(layers "F.Cu" "F.Mask" "F.Paste")
			(net "M_L_CPU0_SB_DQ<15>")
		)
		(pad "CP12" smd circle
			(at -24.589994 24.660098 180)
			(size 0.450088 0.450088)
			(layers "F.Cu" "F.Mask" "F.Paste")
			(net "GND")
		)
		(pad "CP13" smd circle
			(at -23.64994 24.660098 180)
			(size 0.450088 0.450088)
			(layers "F.Cu" "F.Mask" "F.Paste")
			(net "M_H_CPU0_SB_DQ<16>")
		)
		(pad "CP14" smd circle
			(at -22.709886 24.660098 180)
			(size 0.450088 0.450088)
			(layers "F.Cu" "F.Mask" "F.Paste")
			(net "M_H_CPU0_SB_DQ<15>")
		)
		(pad "CP15" smd circle
			(at -21.770086 24.660098 180)
			(size 0.450088 0.450088)
			(layers "F.Cu" "F.Mask" "F.Paste")
			(net "GND")
		)
		(pad "CP16" smd circle
			(at -20.830032 24.660098 180)
			(size 0.450088 0.450088)
			(layers "F.Cu" "F.Mask" "F.Paste")
			(net "M_J_CPU0_SB_DQ<16>")
		)
		(pad "CP17" smd circle
			(at -19.889978 24.660098 180)
			(size 0.450088 0.450088)
			(layers "F.Cu" "F.Mask" "F.Paste")
			(net "GND")
		)
		(pad "CP18" smd circle
			(at -18.949924 24.660098 180)
			(size 0.450088 0.450088)
			(layers "F.Cu" "F.Mask" "F.Paste")
			(net "M_J_CPU0_SB_DQ<15>")
		)
		(pad "CP19" smd circle
			(at -18.010124 24.660098 180)
			(size 0.450088 0.450088)
			(layers "F.Cu" "F.Mask" "F.Paste")
			(net "GND")
		)
		(pad "CP20" smd circle
			(at -17.07007 24.660098 180)
			(size 0.450088 0.450088)
			(layers "F.Cu" "F.Mask" "F.Paste")
			(net "M_I_CPU0_SB_DQ<16>")
		)
		(pad "CP21" smd circle
			(at -16.130016 24.660098 180)
			(size 0.450088 0.450088)
			(layers "F.Cu" "F.Mask" "F.Paste")
			(net "M_I_CPU0_SB_DQ<15>")
		)
		(pad "CP22" smd circle
			(at -15.189962 24.660098 180)
			(size 0.450088 0.450088)
			(layers "F.Cu" "F.Mask" "F.Paste")
			(net "GND")
		)
		(pad "CP23" smd circle
			(at -14.249908 24.660098 180)
			(size 0.450088 0.450088)
			(layers "F.Cu" "F.Mask" "F.Paste")
			(net "PVDDCR_CPU1_P0")
		)
		(pad "CP24" smd circle
			(at -13.310108 24.660098 180)
			(size 0.450088 0.450088)
			(layers "F.Cu" "F.Mask" "F.Paste")
			(net "PVDDCR_CPU1_P0")
		)
		(pad "CP25" smd circle
			(at -12.370054 24.660098 180)
			(size 0.450088 0.450088)
			(layers "F.Cu" "F.Mask" "F.Paste")
			(net "GND")
		)
		(pad "CP26" smd circle
			(at -11.43 24.660098 180)
			(size 0.450088 0.450088)
			(layers "F.Cu" "F.Mask" "F.Paste")
			(net "PVDDCR_CPU1_P0")
		)
		(pad "CP27" smd circle
			(at -10.489946 24.660098 180)
			(size 0.450088 0.450088)
			(layers "F.Cu" "F.Mask" "F.Paste")
			(net "PVDDCR_CPU1_P0")
		)
		(pad "CP28" smd circle
			(at -9.549892 24.660098 180)
			(size 0.450088 0.450088)
			(layers "F.Cu" "F.Mask" "F.Paste")
			(net "GND")
		)
		(pad "CP29" smd circle
			(at -8.610092 24.660098 180)
			(size 0.450088 0.450088)
			(layers "F.Cu" "F.Mask" "F.Paste")
			(net "PVDDCR_CPU1_P0")
		)
		(pad "CP30" smd circle
			(at -7.670038 24.660098 180)
			(size 0.450088 0.450088)
			(layers "F.Cu" "F.Mask" "F.Paste")
			(net "PVDDCR_CPU1_P0")
		)
		(pad "CP31" smd circle
			(at -6.729984 24.660098 180)
			(size 0.450088 0.450088)
			(layers "F.Cu" "F.Mask" "F.Paste")
			(net "GND")
		)
		(pad "CP32" smd circle
			(at -5.78993 24.660098 180)
			(size 0.450088 0.450088)
			(layers "F.Cu" "F.Mask" "F.Paste")
			(net "PVDDCR_CPU1_P0")
		)
		(pad "CP33" smd circle
			(at -4.849876 24.660098 180)
			(size 0.450088 0.450088)
			(layers "F.Cu" "F.Mask" "F.Paste")
			(net "PVDDCR_CPU1_P0")
		)
		(pad "CP34" smd circle
			(at -3.910076 24.660098 180)
			(size 0.450088 0.450088)
			(layers "F.Cu" "F.Mask" "F.Paste")
			(net "GND")
		)
	)
)
